# T6G (Grand Teton) — schematic netlist excerpt (pin names and nets, part order shuffled) for the footprints in the layout excerpt that follows; sources: Cadence DE-HDL packaged netlist, KiCad conversion of 04192023_DAF0TMB3IC0_F0TG_MB_C_brd_V02_OCP.brd

R656  Q_RES  1K 1% EMPTY  pkg 0402LF  page 364 : A = P3V3_AUX ; B = PWRGD_P0V9_RETIMER_CPU1_R
C66  Q_CAP  0.1UF 25V 10% EMPTY  pkg 0402  page 240 : A = FM_FAN_PWR_EN_R ; B = GND

(kicad_pcb
	(version 20260206)
	(generator "pcbnew")
	(generator_version "10.0")
	(general
		(thickness 1.6)
		(legacy_teardrops no)
	)
	(paper "A4")
	(title_block
		(title "04192023_DAF0TMB3IC0_F0TG_MB_C_brd_V02_OCP.brd")
		(comment 1 "Grand Teton / footprints 6154-6155 of 8354")
	)
	(layers
		(0 "F.Cu" signal "TOP")
		(4 "In1.Cu" signal "GND")
		(6 "In2.Cu" signal "IN1")
		(8 "In3.Cu" signal "GND1")
		(10 "In4.Cu" signal "IN2")
		(12 "In5.Cu" signal "GND2")
		(14 "In6.Cu" signal "IN3")
		(16 "In7.Cu" signal "GND3")
		(18 "In8.Cu" signal "VCC")
		(20 "In9.Cu" signal "VCC1")
		(22 "In10.Cu" signal "GND4")
		(24 "In11.Cu" signal "IN4")
		(26 "In12.Cu" signal "GND5")
		(28 "In13.Cu" signal "IN5")
		(30 "In14.Cu" signal "GND6")
		(32 "In15.Cu" signal "IN6")
		(34 "In16.Cu" signal "GND7")
		(2 "B.Cu" signal "BOTTOM")
		(9 "F.Adhes" user "F.Adhesive")
		(11 "B.Adhes" user "B.Adhesive")
		(13 "F.Paste" user "Package Geometry/Pastemask Top")
		(15 "B.Paste" user "Package Geometry/Pastemask Bottom")
		(5 "F.SilkS" user "Ref Des/Silkscreen Top")
		(7 "B.SilkS" user "Ref Des/Silkscreen Bottom")
		(1 "F.Mask" user "Board Geometry/Soldermask Top")
		(3 "B.Mask" user "Board Geometry/Soldermask Bottom")
		(17 "Dwgs.User" user "User.Drawings")
		(19 "Cmts.User" user "User.Comments")
		(21 "Eco1.User" user "User.Eco1")
		(23 "Eco2.User" user "User.Eco2")
		(25 "Edge.Cuts" user "Board Geometry/Outline")
		(27 "Margin" user)
		(31 "F.CrtYd" user "Package Geometry/Place Bound Top")
		(29 "B.CrtYd" user "Package Geometry/Place Bound Bottom")
		(35 "F.Fab" user "Ref Des/Assembly Top")
		(33 "B.Fab" user "Ref Des/Assembly Bottom")
	)
	(footprint ""
		(layer "B.Cu")
		(at 16.985234 -407.10866 -90)
		(property "Reference" "R656"
			(at 0 0 90)
			(layer "B.SilkS")
			(hide yes)
			(effects
				(font
					(size 1.27 1.27)
				)
				(justify mirror)
			)
		)
		(property "Value" ""
			(at 0 0 90)
			(layer "B.Fab")
			(effects
				(font
					(size 1.27 1.27)
				)
				(justify mirror)
			)
		)
		(duplicate_pad_numbers_are_jumpers no)
		(fp_line
			(start -0.7874 0.4064)
			(end 0.7874 0.4064)
			(stroke
				(width 0.1524)
				(type default)
			)
			(layer "B.SilkS")
		)
		(fp_line
			(start 0.7874 0.4064)
			(end 0.7874 -0.4064)
			(stroke
				(width 0.1524)
				(type default)
			)
			(layer "B.SilkS")
		)
		(fp_line
			(start -0.7874 -0.4064)
			(end -0.7874 0.4064)
			(stroke
				(width 0.1524)
				(type default)
			)
			(layer "B.SilkS")
		)
		(fp_line
			(start 0.7874 -0.4064)
			(end -0.7874 -0.4064)
			(stroke
				(width 0.1524)
				(type default)
			)
			(layer "B.SilkS")
		)
		(fp_line
			(start -0.67945 0.3048)
			(end -0.120396 0.3048)
			(stroke
				(width 0.1)
				(type default)
			)
			(layer "B.Fab")
		)
		(fp_line
			(start -0.120396 0.3048)
			(end -0.120396 0.2794)
			(stroke
				(width 0.1)
				(type default)
			)
			(layer "B.Fab")
		)
		(fp_line
			(start 0.12065 0.3048)
			(end 0.67945 0.3048)
			(stroke
				(width 0.1)
				(type default)
			)
			(layer "B.Fab")
		)
		(fp_line
			(start 0.67945 0.3048)
			(end 0.67945 -0.305054)
			(stroke
				(width 0.1)
				(type default)
			)
			(layer "B.Fab")
		)
		(fp_line
			(start -0.120396 0.2794)
			(end 0.12065 0.2794)
			(stroke
				(width 0.1)
				(type default)
			)
			(layer "B.Fab")
		)
		(fp_line
			(start 0.12065 0.2794)
			(end 0.12065 0.3048)
			(stroke
				(width 0.1)
				(type default)
			)
			(layer "B.Fab")
		)
		(fp_line
			(start -0.12065 -0.2794)
			(end -0.12065 -0.3048)
			(stroke
				(width 0.1)
				(type default)
			)
			(layer "B.Fab")
		)
		(fp_line
			(start 0.12065 -0.2794)
			(end -0.12065 -0.2794)
			(stroke
				(width 0.1)
				(type default)
			)
			(layer "B.Fab")
		)
		(fp_line
			(start -0.67945 -0.3048)
			(end -0.67945 0.3048)
			(stroke
				(width 0.1)
				(type default)
			)
			(layer "B.Fab")
		)
		(fp_line
			(start -0.12065 -0.3048)
			(end -0.67945 -0.3048)
			(stroke
				(width 0.1)
				(type default)
			)
			(layer "B.Fab")
		)
		(fp_line
			(start 0.12065 -0.305054)
			(end 0.12065 -0.2794)
			(stroke
				(width 0.1)
				(type default)
			)
			(layer "B.Fab")
		)
		(fp_line
			(start 0.67945 -0.305054)
			(end 0.12065 -0.305054)
			(stroke
				(width 0.1)
				(type default)
			)
			(layer "B.Fab")
		)
		(pad "1" smd circle
			(at 0.40005 0 90)
			(size 0 0)
			(layers "B.Cu" "B.Mask" "B.Paste")
			(net "P3V3_AUX")
		)
		(pad "2" smd circle
			(at -0.40005 0 90)
			(size 0 0)
			(layers "B.Cu" "B.Mask" "B.Paste")
			(net "PWRGD_P0V9_RETIMER_CPU1_R")
		)
	)
	(footprint ""
		(layer "B.Cu")
		(at 240.740692 -422.849548 90)
		(property "Reference" "C66"
			(at 0 0 90)
			(layer "B.SilkS")
			(hide yes)
			(effects
				(font
					(size 1.27 1.27)
				)
				(justify mirror)
			)
		)
		(property "Value" ""
			(at 0 0 90)
			(layer "B.Fab")
			(effects
				(font
					(size 1.27 1.27)
				)
				(justify mirror)
			)
		)
		(duplicate_pad_numbers_are_jumpers no)
		(fp_line
			(start 0.7874 -0.4064)
			(end -0.7874 -0.4064)
			(stroke
				(width 0.1524)
				(type default)
			)
			(layer "B.SilkS")
		)
		(fp_line
			(start -0.7874 -0.4064)
			(end -0.7874 0.4064)
			(stroke
				(width 0.1524)
				(type default)
			)
			(layer "B.SilkS")
		)
		(fp_line
			(start 0.7874 0.4064)
			(end 0.7874 -0.4064)
			(stroke
				(width 0.1524)
				(type default)
			)
			(layer "B.SilkS")
		)
		(fp_line
			(start -0.7874 0.4064)
			(end 0.7874 0.4064)
			(stroke
				(width 0.1524)
				(type default)
			)
			(layer "B.SilkS")
		)
		(fp_line
			(start 0.67945 -0.305054)
			(end 0.12065 -0.305054)
			(stroke
				(width 0.1)
				(type default)
			)
			(layer "B.Fab")
		)
		(fp_line
			(start 0.12065 -0.305054)
			(end 0.12065 -0.2794)
			(stroke
				(width 0.1)
				(type default)
			)
			(layer "B.Fab")
		)
		(fp_line
			(start -0.12065 -0.3048)
			(end -0.67945 -0.3048)
			(stroke
				(width 0.1)
				(type default)
			)
			(layer "B.Fab")
		)
		(fp_line
			(start -0.67945 -0.3048)
			(end -0.67945 0.3048)
			(stroke
				(width 0.1)
				(type default)
			)
			(layer "B.Fab")
		)
		(fp_line
			(start 0.12065 -0.2794)
			(end -0.12065 -0.2794)
			(stroke
				(width 0.1)
				(type default)
			)
			(layer "B.Fab")
		)
		(fp_line
			(start -0.12065 -0.2794)
			(end -0.12065 -0.3048)
			(stroke
				(width 0.1)
				(type default)
			)
			(layer "B.Fab")
		)
		(fp_line
			(start 0.12065 0.2794)
			(end 0.12065 0.3048)
			(stroke
				(width 0.1)
				(type default)
			)
			(layer "B.Fab")
		)
		(fp_line
			(start -0.120396 0.2794)
			(end 0.12065 0.2794)
			(stroke
				(width 0.1)
				(type default)
			)
			(layer "B.Fab")
		)
		(fp_line
			(start 0.67945 0.3048)
			(end 0.67945 -0.305054)
			(stroke
				(width 0.1)
				(type default)
			)
			(layer "B.Fab")
		)
		(fp_line
			(start 0.12065 0.3048)
			(end 0.67945 0.3048)
			(stroke
				(width 0.1)
				(type default)
			)
			(layer "B.Fab")
		)
		(fp_line
			(start -0.120396 0.3048)
			(end -0.120396 0.2794)
			(stroke
				(width 0.1)
				(type default)
			)
			(layer "B.Fab")
		)
		(fp_line
			(start -0.67945 0.3048)
			(end -0.120396 0.3048)
			(stroke
				(width 0.1)
				(type default)
			)
			(layer "B.Fab")
		)
		(pad "1" smd circle
			(at 0.40005 0 270)
			(size 0 0)
			(layers "B.Cu" "B.Mask" "B.Paste")
			(net "FM_FAN_PWR_EN_R")
		)
		(pad "2" smd circle
			(at -0.40005 0 270)
			(size 0 0)
			(layers "B.Cu" "B.Mask" "B.Paste")
			(net "GND")
		)
	)
)
